(kicad_pcb
	(version 20260206)
	(generator "pcbnew")
	(generator_version "10.0")
	(general
		(thickness 1.6)
		(legacy_teardrops no)
	)
	(paper "A4")
	(title_block
		(title "04192023_DAF0TMB3IC0_F0TG_MB_C_brd_V02_OCP.brd")
		(comment 1 "Grand Teton / footprints 231-235 of 8354")
	)
	(layers
		(0 "F.Cu" signal "TOP")
		(4 "In1.Cu" signal "GND")
		(6 "In2.Cu" signal "IN1")
		(8 "In3.Cu" signal "GND1")
		(10 "In4.Cu" signal "IN2")
		(12 "In5.Cu" signal "GND2")
		(14 "In6.Cu" signal "IN3")
		(16 "In7.Cu" signal "GND3")
		(18 "In8.Cu" signal "VCC")
		(20 "In9.Cu" signal "VCC1")
		(22 "In10.Cu" signal "GND4")
		(24 "In11.Cu" signal "IN4")
		(26 "In12.Cu" signal "GND5")
		(28 "In13.Cu" signal "IN5")
		(30 "In14.Cu" signal "GND6")
		(32 "In15.Cu" signal "IN6")
		(34 "In16.Cu" signal "GND7")
		(2 "B.Cu" signal "BOTTOM")
		(9 "F.Adhes" user "F.Adhesive")
		(11 "B.Adhes" user "B.Adhesive")
		(13 "F.Paste" user "Package Geometry/Pastemask Top")
		(15 "B.Paste" user "Package Geometry/Pastemask Bottom")
		(5 "F.SilkS" user "Ref Des/Silkscreen Top")
		(7 "B.SilkS" user "Ref Des/Silkscreen Bottom")
		(1 "F.Mask" user "Board Geometry/Soldermask Top")
		(3 "B.Mask" user "Board Geometry/Soldermask Bottom")
		(17 "Dwgs.User" user "User.Drawings")
		(19 "Cmts.User" user "User.Comments")
		(21 "Eco1.User" user "User.Eco1")
		(23 "Eco2.User" user "User.Eco2")
		(25 "Edge.Cuts" user "Board Geometry/Outline")
		(27 "Margin" user)
		(31 "F.CrtYd" user "Package Geometry/Place Bound Top")
		(29 "B.CrtYd" user "Package Geometry/Place Bound Bottom")
		(35 "F.Fab" user "Ref Des/Assembly Top")
		(33 "B.Fab" user "Ref Des/Assembly Bottom")
	)
	(footprint ""
		(layer "F.Cu")
		(at 76.115164 -17.050512 180)
		(property "Reference" "PR3828"
			(at 0 0 180)
			(layer "F.SilkS")
			(hide yes)
			(effects
				(font
					(size 1.27 1.27)
				)
			)
		)
		(property "Value" ""
			(at 0 0 180)
			(layer "F.Fab")
			(effects
				(font
					(size 1.27 1.27)
				)
			)
		)
		(duplicate_pad_numbers_are_jumpers no)
		(fp_line
			(start 0.7874 0.4064)
			(end -0.7874 0.4064)
			(stroke
				(width 0.1524)
				(type default)
			)
			(layer "F.SilkS")
		)
		(fp_line
			(start 0.7874 -0.4064)
			(end 0.7874 0.4064)
			(stroke
				(width 0.1524)
				(type default)
			)
			(layer "F.SilkS")
		)
		(fp_line
			(start -0.7874 0.4064)
			(end -0.7874 -0.4064)
			(stroke
				(width 0.1524)
				(type default)
			)
			(layer "F.SilkS")
		)
		(fp_line
			(start -0.7874 -0.4064)
			(end 0.7874 -0.4064)
			(stroke
				(width 0.1524)
				(type default)
			)
			(layer "F.SilkS")
		)
		(fp_line
			(start 0.67945 0.3048)
			(end 0.120396 0.3048)
			(stroke
				(width 0.1)
				(type default)
			)
			(layer "F.Fab")
		)
		(fp_line
			(start 0.67945 -0.3048)
			(end 0.67945 0.3048)
			(stroke
				(width 0.1)
				(type default)
			)
			(layer "F.Fab")
		)
		(fp_line
			(start 0.12065 -0.2794)
			(end 0.12065 -0.3048)
			(stroke
				(width 0.1)
				(type default)
			)
			(layer "F.Fab")
		)
		(fp_line
			(start 0.12065 -0.3048)
			(end 0.67945 -0.3048)
			(stroke
				(width 0.1)
				(type default)
			)
			(layer "F.Fab")
		)
		(fp_line
			(start 0.120396 0.3048)
			(end 0.120396 0.2794)
			(stroke
				(width 0.1)
				(type default)
			)
			(layer "F.Fab")
		)
		(fp_line
			(start 0.120396 0.2794)
			(end -0.12065 0.2794)
			(stroke
				(width 0.1)
				(type default)
			)
			(layer "F.Fab")
		)
		(fp_line
			(start -0.12065 0.3048)
			(end -0.67945 0.3048)
			(stroke
				(width 0.1)
				(type default)
			)
			(layer "F.Fab")
		)
		(fp_line
			(start -0.12065 0.2794)
			(end -0.12065 0.3048)
			(stroke
				(width 0.1)
				(type default)
			)
			(layer "F.Fab")
		)
		(fp_line
			(start -0.12065 -0.2794)
			(end 0.12065 -0.2794)
			(stroke
				(width 0.1)
				(type default)
			)
			(layer "F.Fab")
		)
		(fp_line
			(start -0.12065 -0.305054)
			(end -0.12065 -0.2794)
			(stroke
				(width 0.1)
				(type default)
			)
			(layer "F.Fab")
		)
		(fp_line
			(start -0.67945 0.3048)
			(end -0.67945 -0.305054)
			(stroke
				(width 0.1)
				(type default)
			)
			(layer "F.Fab")
		)
		(fp_line
			(start -0.67945 -0.305054)
			(end -0.12065 -0.305054)
			(stroke
				(width 0.1)
				(type default)
			)
			(layer "F.Fab")
		)
		(pad "1" smd circle
			(at -0.40005 0 180)
			(size 0 0)
			(layers "F.Cu" "F.Mask" "F.Paste")
			(net "P12V_OCP_OV_2")
		)
		(pad "2" smd circle
			(at 0.40005 0 180)
			(size 0 0)
			(layers "F.Cu" "F.Mask" "F.Paste")
			(net "GND")
		)
	)
	(footprint ""
		(layer "F.Cu")
		(at 23.229316 -39.824914)
		(property "Reference" "U56"
			(at -1.567942 -4.057904 0)
			(unlocked yes)
			(layer "F.SilkS")
			(effects
				(font
					(size 0.7874 0.5842)
					(thickness 0.1524)
				)
			)
		)
		(property "Value" ""
			(at 0 0 0)
			(layer "F.Fab")
			(effects
				(font
					(size 1.27 1.27)
				)
			)
		)
		(duplicate_pad_numbers_are_jumpers no)
		(fp_line
			(start -1.500124 -1.500124)
			(end -1.004062 -1.500124)
			(stroke
				(width 0.1524)
				(type default)
			)
			(layer "F.SilkS")
		)
		(fp_line
			(start -1.500124 -1.004062)
			(end -1.500124 -1.500124)
			(stroke
				(width 0.1524)
				(type default)
			)
			(layer "F.SilkS")
		)
		(fp_line
			(start -1.500124 1.500124)
			(end -1.500124 1.004062)
			(stroke
				(width 0.1524)
				(type default)
			)
			(layer "F.SilkS")
		)
		(fp_line
			(start -1.004062 1.500124)
			(end -1.500124 1.500124)
			(stroke
				(width 0.1524)
				(type default)
			)
			(layer "F.SilkS")
		)
		(fp_line
			(start 1.004062 -1.500124)
			(end 1.500124 -1.500124)
			(stroke
				(width 0.1524)
				(type default)
			)
			(layer "F.SilkS")
		)
		(fp_line
			(start 1.500124 -1.500124)
			(end 1.500124 -1.004062)
			(stroke
				(width 0.1524)
				(type default)
			)
			(layer "F.SilkS")
		)
		(fp_line
			(start 1.500124 1.004062)
			(end 1.500124 1.500124)
			(stroke
				(width 0.1524)
				(type default)
			)
			(layer "F.SilkS")
		)
		(fp_line
			(start 1.500124 1.500124)
			(end 1.004062 1.500124)
			(stroke
				(width 0.1524)
				(type default)
			)
			(layer "F.SilkS")
		)
		(fp_poly
			(pts
				(xy -2.335784 -2.746502) (xy -3.134868 -2.119122) (xy -2.107946 -1.633728)
			)
			(stroke
				(width 0)
				(type default)
			)
			(fill yes)
			(layer "F.SilkS")
		)
		(fp_line
			(start -1.500124 -1.500124)
			(end 1.500124 -1.500124)
			(stroke
				(width 0.1)
				(type default)
			)
			(layer "F.Fab")
		)
		(fp_line
			(start -1.500124 1.500124)
			(end -1.500124 -1.500124)
			(stroke
				(width 0.1)
				(type default)
			)
			(layer "F.Fab")
		)
		(fp_line
			(start 1.500124 -1.500124)
			(end 1.500124 1.500124)
			(stroke
				(width 0.1)
				(type default)
			)
			(layer "F.Fab")
		)
		(fp_line
			(start 1.500124 1.500124)
			(end -1.500124 1.500124)
			(stroke
				(width 0.1)
				(type default)
			)
			(layer "F.Fab")
		)
		(fp_poly
			(pts
				(xy -2.847848 -1.258062) (xy -2.847848 -0.242062) (xy -1.831848 -0.750062)
			)
			(stroke
				(width 0)
				(type default)
			)
			(fill yes)
			(layer "F.Fab")
		)
		(pad "1" smd rect
			(at -1.400048 -0.750062 270)
			(size 0.2286 0.6096)
			(layers "F.Cu" "F.Mask" "F.Paste")
			(net "INA230_7_A1")
		)
		(pad "2" smd rect
			(at -1.400048 -0.249936 270)
			(size 0.2286 0.6096)
			(layers "F.Cu" "F.Mask" "F.Paste")
			(net "INA230_7_A0")
		)
		(pad "3" smd rect
			(at -1.400048 0.249936 270)
			(size 0.2286 0.6096)
			(layers "F.Cu" "F.Mask" "F.Paste")
			(net "P12V_OCP_V3_2_ADC_ALERT_R")
		)
		(pad "4" smd rect
			(at -1.400048 0.750062 270)
			(size 0.2286 0.6096)
			(layers "F.Cu" "F.Mask" "F.Paste")
			(net "SMB_INA230_7_3V3AUX_SDA_R1")
		)
		(pad "5" smd rect
			(at -0.750062 1.400048)
			(size 0.2286 0.6096)
			(layers "F.Cu" "F.Mask" "F.Paste")
			(net "SMB_INA230_7_3V3AUX_SCL_R1")
		)
		(pad "6" smd rect
			(at -0.249936 1.400048)
			(size 0.2286 0.6096)
			(layers "F.Cu" "F.Mask" "F.Paste")
			(net "NC_INA230_7_NC0")
		)
		(pad "7" smd rect
			(at 0.249936 1.400048)
			(size 0.2286 0.6096)
			(layers "F.Cu" "F.Mask" "F.Paste")
			(net "NC_INA230_7_NC1")
		)
		(pad "8" smd rect
			(at 0.750062 1.400048)
			(size 0.2286 0.6096)
			(layers "F.Cu" "F.Mask" "F.Paste")
			(net "NC_INA230_7_NC2")
		)
		(pad "9" smd rect
			(at 1.400048 0.750062 270)
			(size 0.2286 0.6096)
			(layers "F.Cu" "F.Mask" "F.Paste")
			(net "P3V3_AUX")
		)
		(pad "10" smd rect
			(at 1.400048 0.249936 270)
			(size 0.2286 0.6096)
			(layers "F.Cu" "F.Mask" "F.Paste")
			(net "GND")
		)
		(pad "11" smd rect
			(at 1.400048 -0.249936 270)
			(size 0.2286 0.6096)
			(layers "F.Cu" "F.Mask" "F.Paste")
			(net "P12V_OCP_V3_2")
		)
		(pad "12" smd rect
			(at 1.400048 -0.750062 270)
			(size 0.2286 0.6096)
			(layers "F.Cu" "F.Mask" "F.Paste")
			(net "VSENSE_P12V_INA230_7_INN")
		)
		(pad "13" smd rect
			(at 0.750062 -1.400048)
			(size 0.2286 0.6096)
			(layers "F.Cu" "F.Mask" "F.Paste")
			(net "VSENSE_P12V_INA230_7_INP")
		)
		(pad "14" smd rect
			(at 0.249936 -1.400048)
			(size 0.2286 0.6096)
			(layers "F.Cu" "F.Mask" "F.Paste")
			(net "NC_INA230_7_NC3")
		)
		(pad "15" smd rect
			(at -0.249936 -1.400048)
			(size 0.2286 0.6096)
			(layers "F.Cu" "F.Mask" "F.Paste")
			(net "NC_INA230_7_NC4")
		)
		(pad "16" smd rect
			(at -0.750062 -1.400048)
			(size 0.2286 0.6096)
			(layers "F.Cu" "F.Mask" "F.Paste")
			(net "NC_INA230_7_NC5")
		)
		(pad "TH" smd rect
			(at 0 0)
			(size 1.7018 1.7018)
			(layers "F.Cu" "F.Mask" "F.Paste")
			(net "GND")
		)
		(zone
			(layer "F.Cu")
			(hatch none 0.5)
			(connect_pads
				(clearance 0)
			)
			(min_thickness 0.25)
			(keepout
				(tracks not_allowed)
				(vias allowed)
				(pads allowed)
				(copperpour not_allowed)
				(footprints allowed)
			)
			(placement
				(enabled no)
				(sheetname "")
			)
			(fill
				(thermal_gap 0.5)
				(thermal_bridge_width 0.5)
				(island_removal_mode 0)
			)
			(polygon
				(pts
					(xy 22.184868 -39.850314) (xy 22.184868 -40.869362) (xy 24.273764 -40.869362) (xy 24.273764 -38.780466)
					(xy 22.184868 -38.780466) (xy 22.184868 -39.824914) (xy 22.327616 -39.824914) (xy 22.327616 -38.923214)
					(xy 24.131016 -38.923214) (xy 24.131016 -40.726614) (xy 22.327616 -40.726614) (xy 22.327616 -39.850314)
				)
			)
		)
	)
	(footprint ""
		(layer "F.Cu")
		(at 441.776866 -402.838412 90)
		(property "Reference" "PC6553_1"
			(at 0 0 90)
			(layer "F.SilkS")
			(hide yes)
			(effects
				(font
					(size 1.27 1.27)
				)
			)
		)
		(property "Value" ""
			(at 0 0 90)
			(layer "F.Fab")
			(effects
				(font
					(size 1.27 1.27)
				)
			)
		)
		(duplicate_pad_numbers_are_jumpers no)
		(fp_line
			(start 0.7874 -0.4064)
			(end 0.7874 0.4064)
			(stroke
				(width 0.1524)
				(type default)
			)
			(layer "F.SilkS")
		)
		(fp_line
			(start -0.7874 -0.4064)
			(end 0.7874 -0.4064)
			(stroke
				(width 0.1524)
				(type default)
			)
			(layer "F.SilkS")
		)
		(fp_line
			(start 0.7874 0.4064)
			(end -0.7874 0.4064)
			(stroke
				(width 0.1524)
				(type default)
			)
			(layer "F.SilkS")
		)
		(fp_line
			(start -0.7874 0.4064)
			(end -0.7874 -0.4064)
			(stroke
				(width 0.1524)
				(type default)
			)
			(layer "F.SilkS")
		)
		(fp_line
			(start -0.12065 -0.305054)
			(end -0.12065 -0.2794)
			(stroke
				(width 0.1)
				(type default)
			)
			(layer "F.Fab")
		)
		(fp_line
			(start -0.67945 -0.305054)
			(end -0.12065 -0.305054)
			(stroke
				(width 0.1)
				(type default)
			)
			(layer "F.Fab")
		)
		(fp_line
			(start 0.67945 -0.3048)
			(end 0.67945 0.3048)
			(stroke
				(width 0.1)
				(type default)
			)
			(layer "F.Fab")
		)
		(fp_line
			(start 0.12065 -0.3048)
			(end 0.67945 -0.3048)
			(stroke
				(width 0.1)
				(type default)
			)
			(layer "F.Fab")
		)
		(fp_line
			(start 0.12065 -0.2794)
			(end 0.12065 -0.3048)
			(stroke
				(width 0.1)
				(type default)
			)
			(layer "F.Fab")
		)
		(fp_line
			(start -0.12065 -0.2794)
			(end 0.12065 -0.2794)
			(stroke
				(width 0.1)
				(type default)
			)
			(layer "F.Fab")
		)
		(fp_line
			(start 0.120396 0.2794)
			(end -0.12065 0.2794)
			(stroke
				(width 0.1)
				(type default)
			)
			(layer "F.Fab")
		)
		(fp_line
			(start -0.12065 0.2794)
			(end -0.12065 0.3048)
			(stroke
				(width 0.1)
				(type default)
			)
			(layer "F.Fab")
		)
		(fp_line
			(start 0.67945 0.3048)
			(end 0.120396 0.3048)
			(stroke
				(width 0.1)
				(type default)
			)
			(layer "F.Fab")
		)
		(fp_line
			(start 0.120396 0.3048)
			(end 0.120396 0.2794)
			(stroke
				(width 0.1)
				(type default)
			)
			(layer "F.Fab")
		)
		(fp_line
			(start -0.12065 0.3048)
			(end -0.67945 0.3048)
			(stroke
				(width 0.1)
				(type default)
			)
			(layer "F.Fab")
		)
		(fp_line
			(start -0.67945 0.3048)
			(end -0.67945 -0.305054)
			(stroke
				(width 0.1)
				(type default)
			)
			(layer "F.Fab")
		)
		(pad "1" smd circle
			(at -0.40005 0 90)
			(size 0 0)
			(layers "F.Cu" "F.Mask" "F.Paste")
			(net "PV09_RETIMER_CPU0_VCCS")
		)
		(pad "2" smd circle
			(at 0.40005 0 90)
			(size 0 0)
			(layers "F.Cu" "F.Mask" "F.Paste")
			(net "GND")
		)
	)
	(footprint ""
		(layer "F.Cu")
		(at 191.67983 -362.430568 180)
		(property "Reference" "PC522"
			(at -1.14554 -2.774188 0)
			(unlocked yes)
			(layer "F.SilkS")
			(effects
				(font
					(size 0.7874 0.5842)
					(thickness 0.1524)
				)
				(justify left)
			)
		)
		(property "Value" ""
			(at 0 0 180)
			(layer "F.Fab")
			(effects
				(font
					(size 1.27 1.27)
				)
			)
		)
		(duplicate_pad_numbers_are_jumpers no)
		(fp_line
			(start -3.400044 1.249934)
			(end 3.400044 1.249934)
			(stroke
				(width 0.1524)
				(type default)
			)
			(layer "F.SilkS")
		)
		(fp_circle
			(center 0 1.249934)
			(end -3.400044 1.249934)
			(stroke
				(width 0.1524)
				(type default)
			)
			(fill no)
			(layer "F.SilkS")
		)
		(fp_poly
			(pts
				(arc
					(start 3.400044 1.249934)
					(mid 0 4.649978)
					(end -3.400044 1.249934)
				)
			)
			(stroke
				(width 0)
				(type default)
			)
			(fill yes)
			(layer "F.SilkS")
		)
		(fp_circle
			(center 0 1.249934)
			(end -3.400044 1.249934)
			(stroke
				(width 0.1)
				(type default)
			)
			(fill no)
			(layer "F.Fab")
		)
		(pad "1" thru_hole rect
			(at 0 0 180)
			(size 1.524 1.524)
			(drill 1.016)
			(layers "*.Cu" "*.Mask")
			(remove_unused_layers no)
			(net "SW_P12V_AUX_PVDD11_S3_P1_FLT")
			(clearance 0)
			(padstack
				(mode front_inner_back)
				(layer "Inner"
					(shape circle)
					(size 1.524 1.524)
					(clearance 0)
				)
				(layer "B.Cu"
					(shape rect)
					(size 1.524 1.524)
					(clearance 0)
				)
			)
		)
		(pad "2" thru_hole circle
			(at 0 2.500122 180)
			(size 1.524 1.524)
			(drill 1.016)
			(layers "*.Cu" "*.Mask")
			(remove_unused_layers no)
			(net "GND")
			(clearance 0)
		)
	)
	(footprint ""
		(layer "F.Cu")
		(at 68.42887 -148.21789 -90)
		(property "Reference" "PR8"
			(at 0 0 270)
			(layer "F.SilkS")
			(hide yes)
			(effects
				(font
					(size 1.27 1.27)
				)
			)
		)
		(property "Value" ""
			(at 0 0 270)
			(layer "F.Fab")
			(effects
				(font
					(size 1.27 1.27)
				)
			)
		)
		(duplicate_pad_numbers_are_jumpers no)
		(fp_line
			(start -0.7874 0.4064)
			(end -0.7874 -0.4064)
			(stroke
				(width 0.1524)
				(type default)
			)
			(layer "F.SilkS")
		)
		(fp_line
			(start 0.7874 0.4064)
			(end -0.7874 0.4064)
			(stroke
				(width 0.1524)
				(type default)
			)
			(layer "F.SilkS")
		)
		(fp_line
			(start -0.7874 -0.4064)
			(end 0.7874 -0.4064)
			(stroke
				(width 0.1524)
				(type default)
			)
			(layer "F.SilkS")
		)
		(fp_line
			(start 0.7874 -0.4064)
			(end 0.7874 0.4064)
			(stroke
				(width 0.1524)
				(type default)
			)
			(layer "F.SilkS")
		)
		(fp_line
			(start -0.67945 0.3048)
			(end -0.67945 -0.305054)
			(stroke
				(width 0.1)
				(type default)
			)
			(layer "F.Fab")
		)
		(fp_line
			(start -0.12065 0.3048)
			(end -0.67945 0.3048)
			(stroke
				(width 0.1)
				(type default)
			)
			(layer "F.Fab")
		)
		(fp_line
			(start 0.120396 0.3048)
			(end 0.120396 0.2794)
			(stroke
				(width 0.1)
				(type default)
			)
			(layer "F.Fab")
		)
		(fp_line
			(start 0.67945 0.3048)
			(end 0.120396 0.3048)
			(stroke
				(width 0.1)
				(type default)
			)
			(layer "F.Fab")
		)
		(fp_line
			(start -0.12065 0.2794)
			(end -0.12065 0.3048)
			(stroke
				(width 0.1)
				(type default)
			)
			(layer "F.Fab")
		)
		(fp_line
			(start 0.120396 0.2794)
			(end -0.12065 0.2794)
			(stroke
				(width 0.1)
				(type default)
			)
			(layer "F.Fab")
		)
		(fp_line
			(start -0.12065 -0.2794)
			(end 0.12065 -0.2794)
			(stroke
				(width 0.1)
				(type default)
			)
			(layer "F.Fab")
		)
		(fp_line
			(start 0.12065 -0.2794)
			(end 0.12065 -0.3048)
			(stroke
				(width 0.1)
				(type default)
			)
			(layer "F.Fab")
		)
		(fp_line
			(start 0.12065 -0.3048)
			(end 0.67945 -0.3048)
			(stroke
				(width 0.1)
				(type default)
			)
			(layer "F.Fab")
		)
		(fp_line
			(start 0.67945 -0.3048)
			(end 0.67945 0.3048)
			(stroke
				(width 0.1)
				(type default)
			)
			(layer "F.Fab")
		)
		(fp_line
			(start -0.67945 -0.305054)
			(end -0.12065 -0.305054)
			(stroke
				(width 0.1)
				(type default)
			)
			(layer "F.Fab")
		)
		(fp_line
			(start -0.12065 -0.305054)
			(end -0.12065 -0.2794)
			(stroke
				(width 0.1)
				(type default)
			)
			(layer "F.Fab")
		)
		(pad "1" smd circle
			(at -0.40005 0 270)
			(size 0 0)
			(layers "F.Cu" "F.Mask" "F.Paste")
			(net "PVDD18_S5_P1_CS")
		)
		(pad "2" smd circle
			(at 0.40005 0 270)
			(size 0 0)
			(layers "F.Cu" "F.Mask" "F.Paste")
			(net "GND")
		)
	)
)
